# BASEBOARD_FAB2 (Tioga Pass) — schematic netlist excerpt (pin names and nets, part order shuffled) for the footprints in the layout excerpt that follows; sources: Cadence DE-HDL packaged netlist, KiCad conversion of Wiwynn_Tioga_Pass_MB.brd

R4R2  RES  150.0 1% CHIP  pkg 0402  page 92 : A = PVCCIO_CPU0 ; B = H_CPU0_CATERR_G_N
C1R15  CAP_A  0.1UF 16V 10% X7R  pkg 0402V  page 139 : A = P0V9_LAN ; B = GND
C5U16  CAP  100UF 4V 20% X5R  pkg 0805  page 221 : A = PVTT_ABC ; B = GND

(kicad_pcb
	(version 20260206)
	(generator "pcbnew")
	(generator_version "10.0")
	(general
		(thickness 1.6)
		(legacy_teardrops no)
	)
	(paper "A4")
	(title_block
		(title "Wiwynn_Tioga_Pass_MB.brd")
		(comment 1 "Tioga Pass / footprints 2845-2847 of 4770")
	)
	(layers
		(0 "F.Cu" signal "TOP")
		(4 "In1.Cu" signal "L2GND")
		(6 "In2.Cu" signal "L3")
		(8 "In3.Cu" signal "L4GND")
		(10 "In4.Cu" signal "L5")
		(12 "In5.Cu" signal "L6GND")
		(14 "In6.Cu" signal "L7VCC")
		(16 "In7.Cu" signal "L8VCC")
		(18 "In8.Cu" signal "L9GND")
		(20 "In9.Cu" signal "L10")
		(22 "In10.Cu" signal "L11GND")
		(24 "In11.Cu" signal "L12")
		(26 "In12.Cu" signal "L13GND")
		(2 "B.Cu" signal "BOTTOM")
		(9 "F.Adhes" user "F.Adhesive")
		(11 "B.Adhes" user "B.Adhesive")
		(13 "F.Paste" user "Package Geometry/Pastemask Top")
		(15 "B.Paste" user "Package Geometry/Pastemask Bottom")
		(5 "F.SilkS" user "Ref Des/Silkscreen Top")
		(7 "B.SilkS" user "Ref Des/Silkscreen Bottom")
		(1 "F.Mask" user "Board Geometry/Soldermask Top")
		(3 "B.Mask" user "Board Geometry/Soldermask Bottom")
		(17 "Dwgs.User" user "User.Drawings")
		(19 "Cmts.User" user "User.Comments")
		(21 "Eco1.User" user "User.Eco1")
		(23 "Eco2.User" user "User.Eco2")
		(25 "Edge.Cuts" user "Board Geometry/Outline")
		(27 "Margin" user)
		(31 "F.CrtYd" user "Package Geometry/Place Bound Top")
		(29 "B.CrtYd" user "Package Geometry/Place Bound Bottom")
		(35 "F.Fab" user "Ref Des/Assembly Top")
		(33 "B.Fab" user "Ref Des/Assembly Bottom")
	)
	(footprint ""
		(layer "B.Cu")
		(at 327.914 -61.849 -90)
		(property "Reference" "R4R2"
			(at 0 0 90)
			(layer "B.SilkS")
			(hide yes)
			(effects
				(font
					(size 1.27 1.27)
				)
				(justify mirror)
			)
		)
		(property "Value" ""
			(at 0 0 90)
			(layer "B.Fab")
			(effects
				(font
					(size 1.27 1.27)
				)
				(justify mirror)
			)
		)
		(duplicate_pad_numbers_are_jumpers no)
		(fp_poly
			(pts
				(xy 0.2794 -0.1016) (xy -0.2794 -0.1016) (xy -0.2794 0.9906) (xy 0.2794 0.9906)
			)
			(stroke
				(width 0)
				(type default)
			)
			(fill no)
			(layer "B.CrtYd")
		)
		(fp_line
			(start -0.2794 0.9906)
			(end -0.2794 -0.1016)
			(stroke
				(width 0.1)
				(type default)
			)
			(layer "B.Fab")
		)
		(fp_line
			(start 0.2794 0.9906)
			(end -0.2794 0.9906)
			(stroke
				(width 0.1)
				(type default)
			)
			(layer "B.Fab")
		)
		(fp_line
			(start -0.2794 -0.1016)
			(end 0.2794 -0.1016)
			(stroke
				(width 0.1)
				(type default)
			)
			(layer "B.Fab")
		)
		(fp_line
			(start 0.2794 -0.1016)
			(end 0.2794 0.9906)
			(stroke
				(width 0.1)
				(type default)
			)
			(layer "B.Fab")
		)
		(pad "1" smd rect
			(at 0 0 90)
			(size 0.508 0.508)
			(layers "B.Cu" "B.Mask" "B.Paste")
			(net "PVCCIO_CPU0")
		)
		(pad "2" smd rect
			(at 0 0.889 90)
			(size 0.508 0.508)
			(layers "B.Cu" "B.Mask" "B.Paste")
			(net "H_CPU0_CATERR_G_N")
		)
		(zone
			(layer "B.Cu")
			(hatch none 0.5)
			(connect_pads
				(clearance 0)
			)
			(min_thickness 0.25)
			(keepout
				(tracks not_allowed)
				(vias allowed)
				(pads allowed)
				(copperpour not_allowed)
				(footprints allowed)
			)
			(placement
				(enabled no)
				(sheetname "")
			)
			(fill
				(thermal_gap 0.5)
				(thermal_bridge_width 0.5)
				(island_removal_mode 0)
			)
			(polygon
				(pts
					(xy 327.279 -61.595) (xy 327.279 -62.103) (xy 327.66 -62.103) (xy 327.66 -61.595)
				)
			)
		)
		(zone
			(layer "B.Cu")
			(hatch none 0.5)
			(connect_pads
				(clearance 0)
			)
			(min_thickness 0.25)
			(keepout
				(tracks allowed)
				(vias not_allowed)
				(pads allowed)
				(copperpour not_allowed)
				(footprints allowed)
			)
			(placement
				(enabled no)
				(sheetname "")
			)
			(fill
				(thermal_gap 0.5)
				(thermal_bridge_width 0.5)
				(island_removal_mode 0)
			)
			(polygon
				(pts
					(xy 327.66 -61.595) (xy 327.66 -62.103) (xy 327.279 -62.103) (xy 327.279 -61.595)
				)
			)
		)
	)
	(footprint ""
		(layer "B.Cu")
		(at 259.999734 4.003548 90)
		(property "Reference" "C5U16"
			(at -1.47828 0.78994 180)
			(unlocked yes)
			(layer "B.SilkS")
			(effects
				(font
					(size 0.4064 0.254)
					(thickness 0.1524)
				)
				(justify mirror)
			)
		)
		(property "Value" ""
			(at 0 0 90)
			(layer "B.Fab")
			(effects
				(font
					(size 1.27 1.27)
				)
				(justify mirror)
			)
		)
		(duplicate_pad_numbers_are_jumpers no)
		(fp_poly
			(pts
				(xy 0.7239 -0.2159) (xy -0.7239 -0.2159) (xy -0.7239 1.9939) (xy 0.7239 1.9939)
			)
			(stroke
				(width 0)
				(type default)
			)
			(fill no)
			(layer "B.CrtYd")
		)
		(fp_line
			(start 0.7239 -0.2159)
			(end 0.7239 1.9939)
			(stroke
				(width 0.1)
				(type default)
			)
			(layer "B.Fab")
		)
		(fp_line
			(start -0.7239 -0.2159)
			(end 0.7239 -0.2159)
			(stroke
				(width 0.1)
				(type default)
			)
			(layer "B.Fab")
		)
		(fp_line
			(start 0.7239 1.9939)
			(end -0.7239 1.9939)
			(stroke
				(width 0.1)
				(type default)
			)
			(layer "B.Fab")
		)
		(fp_line
			(start -0.7239 1.9939)
			(end -0.7239 -0.2159)
			(stroke
				(width 0.1)
				(type default)
			)
			(layer "B.Fab")
		)
		(pad "1" smd rect
			(at 0 0 270)
			(size 1.27 1.016)
			(layers "B.Cu" "B.Mask" "B.Paste")
			(net "PVTT_ABC")
		)
		(pad "2" smd rect
			(at 0 1.778 270)
			(size 1.27 1.016)
			(layers "B.Cu" "B.Mask" "B.Paste")
			(net "GND")
		)
		(zone
			(layer "B.Cu")
			(hatch none 0.5)
			(connect_pads
				(clearance 0)
			)
			(min_thickness 0.25)
			(keepout
				(tracks not_allowed)
				(vias allowed)
				(pads allowed)
				(copperpour not_allowed)
				(footprints allowed)
			)
			(placement
				(enabled no)
				(sheetname "")
			)
			(fill
				(thermal_gap 0.5)
				(thermal_bridge_width 0.5)
				(island_removal_mode 0)
			)
			(polygon
				(pts
					(xy 260.507734 3.368548) (xy 260.507734 4.638548) (xy 261.269734 4.638548) (xy 261.269734 3.368548)
				)
			)
		)
	)
	(footprint ""
		(layer "B.Cu")
		(at 482.2825 -47.625 90)
		(property "Reference" "C1R15"
			(at 0 0 90)
			(layer "B.SilkS")
			(hide yes)
			(effects
				(font
					(size 1.27 1.27)
				)
				(justify mirror)
			)
		)
		(property "Value" ""
			(at 0 0 90)
			(layer "B.Fab")
			(effects
				(font
					(size 1.27 1.27)
				)
				(justify mirror)
			)
		)
		(duplicate_pad_numbers_are_jumpers no)
		(fp_poly
			(pts
				(xy -0.3048 -0.1016) (xy -0.3048 0.9906) (xy 0.3048 0.9906) (xy 0.3048 -0.1016)
			)
			(stroke
				(width 0)
				(type default)
			)
			(fill no)
			(layer "B.CrtYd")
		)
		(fp_line
			(start 0.3048 -0.1016)
			(end 0.3048 0.9906)
			(stroke
				(width 0.1)
				(type default)
			)
			(layer "B.Fab")
		)
		(fp_line
			(start -0.3048 -0.1016)
			(end 0.3048 -0.1016)
			(stroke
				(width 0.1)
				(type default)
			)
			(layer "B.Fab")
		)
		(fp_line
			(start 0.3048 0.9906)
			(end -0.3048 0.9906)
			(stroke
				(width 0.1)
				(type default)
			)
			(layer "B.Fab")
		)
		(fp_line
			(start -0.3048 0.9906)
			(end -0.3048 -0.1016)
			(stroke
				(width 0.1)
				(type default)
			)
			(layer "B.Fab")
		)
		(pad "1" smd rect
			(at 0 0 270)
			(size 0.508 0.508)
			(layers "B.Cu" "B.Mask" "B.Paste")
			(net "P0V9_LAN")
		)
		(pad "2" smd rect
			(at 0 0.889 270)
			(size 0.508 0.508)
			(layers "B.Cu" "B.Mask" "B.Paste")
			(net "GND")
		)
		(zone
			(layer "B.Cu")
			(hatch none 0.5)
			(connect_pads
				(clearance 0)
			)
			(min_thickness 0.25)
			(keepout
				(tracks allowed)
				(vias not_allowed)
				(pads allowed)
				(copperpour not_allowed)
				(footprints allowed)
			)
			(placement
				(enabled no)
				(sheetname "")
			)
			(fill
				(thermal_gap 0.5)
				(thermal_bridge_width 0.5)
				(island_removal_mode 0)
			)
			(polygon
				(pts
					(xy 482.5365 -47.879) (xy 482.5365 -47.371) (xy 482.9175 -47.371) (xy 482.9175 -47.879)
				)
			)
		)
		(zone
			(layer "B.Cu")
			(hatch none 0.5)
			(connect_pads
				(clearance 0)
			)
			(min_thickness 0.25)
			(keepout
				(tracks not_allowed)
				(vias allowed)
				(pads allowed)
				(copperpour not_allowed)
				(footprints allowed)
			)
			(placement
				(enabled no)
				(sheetname "")
			)
			(fill
				(thermal_gap 0.5)
				(thermal_bridge_width 0.5)
				(island_removal_mode 0)
			)
			(polygon
				(pts
					(xy 482.9175 -47.879) (xy 482.9175 -47.371) (xy 482.5365 -47.371) (xy 482.5365 -47.879)
				)
			)
		)
	)
)
